(kicad_pcb
	(version 20260206)
	(generator "pcbnew")
	(generator_version "10.0")
	(general
		(thickness 1.6)
		(legacy_teardrops no)
	)
	(paper "A4")
	(title_block
		(title "9052_F0T_PDB_Converter_Brick_F_V03_1208_1600_OCP.brd")
		(comment 1 "Grand Teton / footprints 523-528 of 578")
	)
	(layers
		(0 "F.Cu" signal "TOP")
		(4 "In1.Cu" signal "GND")
		(6 "In2.Cu" signal "IN1")
		(8 "In3.Cu" signal "GND1")
		(10 "In4.Cu" signal "VCC")
		(12 "In5.Cu" signal "VCC1")
		(14 "In6.Cu" signal "GND2")
		(16 "In7.Cu" signal "IN2")
		(18 "In8.Cu" signal "GND3")
		(2 "B.Cu" signal "BOTTOM")
		(9 "F.Adhes" user "F.Adhesive")
		(11 "B.Adhes" user "B.Adhesive")
		(13 "F.Paste" user "Package Geometry/Pastemask Top")
		(15 "B.Paste" user "Package Geometry/Pastemask Bottom")
		(5 "F.SilkS" user "Ref Des/Silkscreen Top")
		(7 "B.SilkS" user "Ref Des/Silkscreen Bottom")
		(1 "F.Mask" user "Board Geometry/Soldermask Top")
		(3 "B.Mask" user "Board Geometry/Soldermask Bottom")
		(17 "Dwgs.User" user "User.Drawings")
		(19 "Cmts.User" user "User.Comments")
		(21 "Eco1.User" user "User.Eco1")
		(23 "Eco2.User" user "User.Eco2")
		(25 "Edge.Cuts" user "Board Geometry/Outline")
		(27 "Margin" user)
		(31 "F.CrtYd" user "Package Geometry/Place Bound Top")
		(29 "B.CrtYd" user "Package Geometry/Place Bound Bottom")
		(35 "F.Fab" user "Ref Des/Assembly Top")
		(33 "B.Fab" user "Ref Des/Assembly Bottom")
	)
	(footprint ""
		(layer "B.Cu")
		(at 266.192 -31.877)
		(property "Reference" "PR212"
			(at 0 0 0)
			(layer "B.SilkS")
			(hide yes)
			(effects
				(font
					(size 1.27 1.27)
				)
				(justify mirror)
			)
		)
		(property "Value" ""
			(at 0 0 0)
			(layer "B.Fab")
			(effects
				(font
					(size 1.27 1.27)
				)
				(justify mirror)
			)
		)
		(duplicate_pad_numbers_are_jumpers no)
		(fp_line
			(start -0.7874 -0.4064)
			(end -0.7874 0.4064)
			(stroke
				(width 0.1524)
				(type default)
			)
			(layer "B.SilkS")
		)
		(fp_line
			(start -0.7874 0.4064)
			(end 0.7874 0.4064)
			(stroke
				(width 0.1524)
				(type default)
			)
			(layer "B.SilkS")
		)
		(fp_line
			(start 0.7874 -0.4064)
			(end -0.7874 -0.4064)
			(stroke
				(width 0.1524)
				(type default)
			)
			(layer "B.SilkS")
		)
		(fp_line
			(start 0.7874 0.4064)
			(end 0.7874 -0.4064)
			(stroke
				(width 0.1524)
				(type default)
			)
			(layer "B.SilkS")
		)
		(fp_line
			(start -0.67945 -0.3048)
			(end -0.67945 0.3048)
			(stroke
				(width 0.1)
				(type default)
			)
			(layer "B.Fab")
		)
		(fp_line
			(start -0.67945 0.3048)
			(end -0.120396 0.3048)
			(stroke
				(width 0.1)
				(type default)
			)
			(layer "B.Fab")
		)
		(fp_line
			(start -0.12065 -0.3048)
			(end -0.67945 -0.3048)
			(stroke
				(width 0.1)
				(type default)
			)
			(layer "B.Fab")
		)
		(fp_line
			(start -0.12065 -0.2794)
			(end -0.12065 -0.3048)
			(stroke
				(width 0.1)
				(type default)
			)
			(layer "B.Fab")
		)
		(fp_line
			(start -0.120396 0.2794)
			(end 0.12065 0.2794)
			(stroke
				(width 0.1)
				(type default)
			)
			(layer "B.Fab")
		)
		(fp_line
			(start -0.120396 0.3048)
			(end -0.120396 0.2794)
			(stroke
				(width 0.1)
				(type default)
			)
			(layer "B.Fab")
		)
		(fp_line
			(start 0.12065 -0.305054)
			(end 0.12065 -0.2794)
			(stroke
				(width 0.1)
				(type default)
			)
			(layer "B.Fab")
		)
		(fp_line
			(start 0.12065 -0.2794)
			(end -0.12065 -0.2794)
			(stroke
				(width 0.1)
				(type default)
			)
			(layer "B.Fab")
		)
		(fp_line
			(start 0.12065 0.2794)
			(end 0.12065 0.3048)
			(stroke
				(width 0.1)
				(type default)
			)
			(layer "B.Fab")
		)
		(fp_line
			(start 0.12065 0.3048)
			(end 0.67945 0.3048)
			(stroke
				(width 0.1)
				(type default)
			)
			(layer "B.Fab")
		)
		(fp_line
			(start 0.67945 -0.305054)
			(end 0.12065 -0.305054)
			(stroke
				(width 0.1)
				(type default)
			)
			(layer "B.Fab")
		)
		(fp_line
			(start 0.67945 0.3048)
			(end 0.67945 -0.305054)
			(stroke
				(width 0.1)
				(type default)
			)
			(layer "B.Fab")
		)
		(pad "1" smd circle
			(at 0.40005 0 180)
			(size 0 0)
			(layers "B.Cu" "B.Mask" "B.Paste")
			(net "P52V_HS1_SIO")
		)
		(pad "2" smd circle
			(at -0.40005 0 180)
			(size 0 0)
			(layers "B.Cu" "B.Mask" "B.Paste")
			(net "P52V_HS1_INTVCC")
		)
	)
	(footprint ""
		(layer "B.Cu")
		(at 279.908 -45.72 180)
		(property "Reference" "R156"
			(at 0 0 0)
			(layer "B.SilkS")
			(hide yes)
			(effects
				(font
					(size 1.27 1.27)
				)
				(justify mirror)
			)
		)
		(property "Value" ""
			(at 0 0 0)
			(layer "B.Fab")
			(effects
				(font
					(size 1.27 1.27)
				)
				(justify mirror)
			)
		)
		(duplicate_pad_numbers_are_jumpers no)
		(fp_line
			(start 0.7874 0.4064)
			(end 0.7874 -0.4064)
			(stroke
				(width 0.1524)
				(type default)
			)
			(layer "B.SilkS")
		)
		(fp_line
			(start 0.7874 -0.4064)
			(end -0.7874 -0.4064)
			(stroke
				(width 0.1524)
				(type default)
			)
			(layer "B.SilkS")
		)
		(fp_line
			(start -0.7874 0.4064)
			(end 0.7874 0.4064)
			(stroke
				(width 0.1524)
				(type default)
			)
			(layer "B.SilkS")
		)
		(fp_line
			(start -0.7874 -0.4064)
			(end -0.7874 0.4064)
			(stroke
				(width 0.1524)
				(type default)
			)
			(layer "B.SilkS")
		)
		(fp_line
			(start 0.67945 0.3048)
			(end 0.67945 -0.305054)
			(stroke
				(width 0.1)
				(type default)
			)
			(layer "B.Fab")
		)
		(fp_line
			(start 0.67945 -0.305054)
			(end 0.12065 -0.305054)
			(stroke
				(width 0.1)
				(type default)
			)
			(layer "B.Fab")
		)
		(fp_line
			(start 0.12065 0.3048)
			(end 0.67945 0.3048)
			(stroke
				(width 0.1)
				(type default)
			)
			(layer "B.Fab")
		)
		(fp_line
			(start 0.12065 0.2794)
			(end 0.12065 0.3048)
			(stroke
				(width 0.1)
				(type default)
			)
			(layer "B.Fab")
		)
		(fp_line
			(start 0.12065 -0.2794)
			(end -0.12065 -0.2794)
			(stroke
				(width 0.1)
				(type default)
			)
			(layer "B.Fab")
		)
		(fp_line
			(start 0.12065 -0.305054)
			(end 0.12065 -0.2794)
			(stroke
				(width 0.1)
				(type default)
			)
			(layer "B.Fab")
		)
		(fp_line
			(start -0.120396 0.3048)
			(end -0.120396 0.2794)
			(stroke
				(width 0.1)
				(type default)
			)
			(layer "B.Fab")
		)
		(fp_line
			(start -0.120396 0.2794)
			(end 0.12065 0.2794)
			(stroke
				(width 0.1)
				(type default)
			)
			(layer "B.Fab")
		)
		(fp_line
			(start -0.12065 -0.2794)
			(end -0.12065 -0.3048)
			(stroke
				(width 0.1)
				(type default)
			)
			(layer "B.Fab")
		)
		(fp_line
			(start -0.12065 -0.3048)
			(end -0.67945 -0.3048)
			(stroke
				(width 0.1)
				(type default)
			)
			(layer "B.Fab")
		)
		(fp_line
			(start -0.67945 0.3048)
			(end -0.120396 0.3048)
			(stroke
				(width 0.1)
				(type default)
			)
			(layer "B.Fab")
		)
		(fp_line
			(start -0.67945 -0.3048)
			(end -0.67945 0.3048)
			(stroke
				(width 0.1)
				(type default)
			)
			(layer "B.Fab")
		)
		(pad "1" smd circle
			(at 0.40005 0)
			(size 0 0)
			(layers "B.Cu" "B.Mask" "B.Paste")
			(net "P52V_HS1_VCAP")
		)
		(pad "2" smd circle
			(at -0.40005 0)
			(size 0 0)
			(layers "B.Cu" "B.Mask" "B.Paste")
			(net "P52V_HS1_ADR0")
		)
	)
	(footprint ""
		(layer "B.Cu")
		(at 139.065 -78.867)
		(property "Reference" "R161"
			(at 0 0 0)
			(layer "B.SilkS")
			(hide yes)
			(effects
				(font
					(size 1.27 1.27)
				)
				(justify mirror)
			)
		)
		(property "Value" ""
			(at 0 0 0)
			(layer "B.Fab")
			(effects
				(font
					(size 1.27 1.27)
				)
				(justify mirror)
			)
		)
		(duplicate_pad_numbers_are_jumpers no)
		(fp_line
			(start -0.7874 -0.4064)
			(end -0.7874 0.4064)
			(stroke
				(width 0.1524)
				(type default)
			)
			(layer "B.SilkS")
		)
		(fp_line
			(start -0.7874 0.4064)
			(end 0.7874 0.4064)
			(stroke
				(width 0.1524)
				(type default)
			)
			(layer "B.SilkS")
		)
		(fp_line
			(start 0.7874 -0.4064)
			(end -0.7874 -0.4064)
			(stroke
				(width 0.1524)
				(type default)
			)
			(layer "B.SilkS")
		)
		(fp_line
			(start 0.7874 0.4064)
			(end 0.7874 -0.4064)
			(stroke
				(width 0.1524)
				(type default)
			)
			(layer "B.SilkS")
		)
		(fp_line
			(start -0.67945 -0.3048)
			(end -0.67945 0.3048)
			(stroke
				(width 0.1)
				(type default)
			)
			(layer "B.Fab")
		)
		(fp_line
			(start -0.67945 0.3048)
			(end -0.120396 0.3048)
			(stroke
				(width 0.1)
				(type default)
			)
			(layer "B.Fab")
		)
		(fp_line
			(start -0.12065 -0.3048)
			(end -0.67945 -0.3048)
			(stroke
				(width 0.1)
				(type default)
			)
			(layer "B.Fab")
		)
		(fp_line
			(start -0.12065 -0.2794)
			(end -0.12065 -0.3048)
			(stroke
				(width 0.1)
				(type default)
			)
			(layer "B.Fab")
		)
		(fp_line
			(start -0.120396 0.2794)
			(end 0.12065 0.2794)
			(stroke
				(width 0.1)
				(type default)
			)
			(layer "B.Fab")
		)
		(fp_line
			(start -0.120396 0.3048)
			(end -0.120396 0.2794)
			(stroke
				(width 0.1)
				(type default)
			)
			(layer "B.Fab")
		)
		(fp_line
			(start 0.12065 -0.305054)
			(end 0.12065 -0.2794)
			(stroke
				(width 0.1)
				(type default)
			)
			(layer "B.Fab")
		)
		(fp_line
			(start 0.12065 -0.2794)
			(end -0.12065 -0.2794)
			(stroke
				(width 0.1)
				(type default)
			)
			(layer "B.Fab")
		)
		(fp_line
			(start 0.12065 0.2794)
			(end 0.12065 0.3048)
			(stroke
				(width 0.1)
				(type default)
			)
			(layer "B.Fab")
		)
		(fp_line
			(start 0.12065 0.3048)
			(end 0.67945 0.3048)
			(stroke
				(width 0.1)
				(type default)
			)
			(layer "B.Fab")
		)
		(fp_line
			(start 0.67945 -0.305054)
			(end 0.12065 -0.305054)
			(stroke
				(width 0.1)
				(type default)
			)
			(layer "B.Fab")
		)
		(fp_line
			(start 0.67945 0.3048)
			(end 0.67945 -0.305054)
			(stroke
				(width 0.1)
				(type default)
			)
			(layer "B.Fab")
		)
		(pad "1" smd circle
			(at 0.40005 0 180)
			(size 0 0)
			(layers "B.Cu" "B.Mask" "B.Paste")
			(net "P3V3_AUX")
		)
		(pad "2" smd circle
			(at -0.40005 0 180)
			(size 0 0)
			(layers "B.Cu" "B.Mask" "B.Paste")
			(net "SMB_P52V_VPDB_SCL")
		)
	)
	(footprint ""
		(layer "B.Cu")
		(at 225.552 -70.993 -90)
		(property "Reference" "R71"
			(at 0 0 90)
			(layer "B.SilkS")
			(hide yes)
			(effects
				(font
					(size 1.27 1.27)
				)
				(justify mirror)
			)
		)
		(property "Value" ""
			(at 0 0 90)
			(layer "B.Fab")
			(effects
				(font
					(size 1.27 1.27)
				)
				(justify mirror)
			)
		)
		(duplicate_pad_numbers_are_jumpers no)
		(fp_line
			(start -0.7874 0.4064)
			(end 0.7874 0.4064)
			(stroke
				(width 0.1524)
				(type default)
			)
			(layer "B.SilkS")
		)
		(fp_line
			(start 0.7874 0.4064)
			(end 0.7874 -0.4064)
			(stroke
				(width 0.1524)
				(type default)
			)
			(layer "B.SilkS")
		)
		(fp_line
			(start -0.7874 -0.4064)
			(end -0.7874 0.4064)
			(stroke
				(width 0.1524)
				(type default)
			)
			(layer "B.SilkS")
		)
		(fp_line
			(start 0.7874 -0.4064)
			(end -0.7874 -0.4064)
			(stroke
				(width 0.1524)
				(type default)
			)
			(layer "B.SilkS")
		)
		(fp_line
			(start -0.67945 0.3048)
			(end -0.120396 0.3048)
			(stroke
				(width 0.1)
				(type default)
			)
			(layer "B.Fab")
		)
		(fp_line
			(start -0.120396 0.3048)
			(end -0.120396 0.2794)
			(stroke
				(width 0.1)
				(type default)
			)
			(layer "B.Fab")
		)
		(fp_line
			(start 0.12065 0.3048)
			(end 0.67945 0.3048)
			(stroke
				(width 0.1)
				(type default)
			)
			(layer "B.Fab")
		)
		(fp_line
			(start 0.67945 0.3048)
			(end 0.67945 -0.305054)
			(stroke
				(width 0.1)
				(type default)
			)
			(layer "B.Fab")
		)
		(fp_line
			(start -0.120396 0.2794)
			(end 0.12065 0.2794)
			(stroke
				(width 0.1)
				(type default)
			)
			(layer "B.Fab")
		)
		(fp_line
			(start 0.12065 0.2794)
			(end 0.12065 0.3048)
			(stroke
				(width 0.1)
				(type default)
			)
			(layer "B.Fab")
		)
		(fp_line
			(start -0.12065 -0.2794)
			(end -0.12065 -0.3048)
			(stroke
				(width 0.1)
				(type default)
			)
			(layer "B.Fab")
		)
		(fp_line
			(start 0.12065 -0.2794)
			(end -0.12065 -0.2794)
			(stroke
				(width 0.1)
				(type default)
			)
			(layer "B.Fab")
		)
		(fp_line
			(start -0.67945 -0.3048)
			(end -0.67945 0.3048)
			(stroke
				(width 0.1)
				(type default)
			)
			(layer "B.Fab")
		)
		(fp_line
			(start -0.12065 -0.3048)
			(end -0.67945 -0.3048)
			(stroke
				(width 0.1)
				(type default)
			)
			(layer "B.Fab")
		)
		(fp_line
			(start 0.12065 -0.305054)
			(end 0.12065 -0.2794)
			(stroke
				(width 0.1)
				(type default)
			)
			(layer "B.Fab")
		)
		(fp_line
			(start 0.67945 -0.305054)
			(end 0.12065 -0.305054)
			(stroke
				(width 0.1)
				(type default)
			)
			(layer "B.Fab")
		)
		(pad "1" smd circle
			(at 0.40005 0 90)
			(size 0 0)
			(layers "B.Cu" "B.Mask" "B.Paste")
			(net "GPU_HSC_R_EN")
		)
		(pad "2" smd circle
			(at -0.40005 0 90)
			(size 0 0)
			(layers "B.Cu" "B.Mask" "B.Paste")
			(net "GPU_HSC_EN")
		)
	)
	(footprint ""
		(layer "B.Cu")
		(at 189.611 -83.439)
		(property "Reference" "R128"
			(at 0 0 0)
			(layer "B.SilkS")
			(hide yes)
			(effects
				(font
					(size 1.27 1.27)
				)
				(justify mirror)
			)
		)
		(property "Value" ""
			(at 0 0 0)
			(layer "B.Fab")
			(effects
				(font
					(size 1.27 1.27)
				)
				(justify mirror)
			)
		)
		(duplicate_pad_numbers_are_jumpers no)
		(fp_line
			(start -0.7874 -0.4064)
			(end -0.7874 0.4064)
			(stroke
				(width 0.1524)
				(type default)
			)
			(layer "B.SilkS")
		)
		(fp_line
			(start -0.7874 0.4064)
			(end 0.7874 0.4064)
			(stroke
				(width 0.1524)
				(type default)
			)
			(layer "B.SilkS")
		)
		(fp_line
			(start 0.7874 -0.4064)
			(end -0.7874 -0.4064)
			(stroke
				(width 0.1524)
				(type default)
			)
			(layer "B.SilkS")
		)
		(fp_line
			(start 0.7874 0.4064)
			(end 0.7874 -0.4064)
			(stroke
				(width 0.1524)
				(type default)
			)
			(layer "B.SilkS")
		)
		(fp_line
			(start -0.67945 -0.3048)
			(end -0.67945 0.3048)
			(stroke
				(width 0.1)
				(type default)
			)
			(layer "B.Fab")
		)
		(fp_line
			(start -0.67945 0.3048)
			(end -0.120396 0.3048)
			(stroke
				(width 0.1)
				(type default)
			)
			(layer "B.Fab")
		)
		(fp_line
			(start -0.12065 -0.3048)
			(end -0.67945 -0.3048)
			(stroke
				(width 0.1)
				(type default)
			)
			(layer "B.Fab")
		)
		(fp_line
			(start -0.12065 -0.2794)
			(end -0.12065 -0.3048)
			(stroke
				(width 0.1)
				(type default)
			)
			(layer "B.Fab")
		)
		(fp_line
			(start -0.120396 0.2794)
			(end 0.12065 0.2794)
			(stroke
				(width 0.1)
				(type default)
			)
			(layer "B.Fab")
		)
		(fp_line
			(start -0.120396 0.3048)
			(end -0.120396 0.2794)
			(stroke
				(width 0.1)
				(type default)
			)
			(layer "B.Fab")
		)
		(fp_line
			(start 0.12065 -0.305054)
			(end 0.12065 -0.2794)
			(stroke
				(width 0.1)
				(type default)
			)
			(layer "B.Fab")
		)
		(fp_line
			(start 0.12065 -0.2794)
			(end -0.12065 -0.2794)
			(stroke
				(width 0.1)
				(type default)
			)
			(layer "B.Fab")
		)
		(fp_line
			(start 0.12065 0.2794)
			(end 0.12065 0.3048)
			(stroke
				(width 0.1)
				(type default)
			)
			(layer "B.Fab")
		)
		(fp_line
			(start 0.12065 0.3048)
			(end 0.67945 0.3048)
			(stroke
				(width 0.1)
				(type default)
			)
			(layer "B.Fab")
		)
		(fp_line
			(start 0.67945 -0.305054)
			(end 0.12065 -0.305054)
			(stroke
				(width 0.1)
				(type default)
			)
			(layer "B.Fab")
		)
		(fp_line
			(start 0.67945 0.3048)
			(end 0.67945 -0.305054)
			(stroke
				(width 0.1)
				(type default)
			)
			(layer "B.Fab")
		)
		(pad "1" smd circle
			(at 0.40005 0 180)
			(size 0 0)
			(layers "B.Cu" "B.Mask" "B.Paste")
			(net "SMB_P52V_VPDB_SDA")
		)
		(pad "2" smd circle
			(at -0.40005 0 180)
			(size 0 0)
			(layers "B.Cu" "B.Mask" "B.Paste")
			(net "P3V3_AUX")
		)
	)
	(footprint ""
		(layer "B.Cu")
		(at 189.611 -89.7128)
		(property "Reference" "R131"
			(at 0 0 0)
			(layer "B.SilkS")
			(hide yes)
			(effects
				(font
					(size 1.27 1.27)
				)
				(justify mirror)
			)
		)
		(property "Value" ""
			(at 0 0 0)
			(layer "B.Fab")
			(effects
				(font
					(size 1.27 1.27)
				)
				(justify mirror)
			)
		)
		(duplicate_pad_numbers_are_jumpers no)
		(fp_line
			(start -0.7874 -0.4064)
			(end -0.7874 0.4064)
			(stroke
				(width 0.1524)
				(type default)
			)
			(layer "B.SilkS")
		)
		(fp_line
			(start -0.7874 0.4064)
			(end 0.7874 0.4064)
			(stroke
				(width 0.1524)
				(type default)
			)
			(layer "B.SilkS")
		)
		(fp_line
			(start 0.7874 -0.4064)
			(end -0.7874 -0.4064)
			(stroke
				(width 0.1524)
				(type default)
			)
			(layer "B.SilkS")
		)
		(fp_line
			(start 0.7874 0.4064)
			(end 0.7874 -0.4064)
			(stroke
				(width 0.1524)
				(type default)
			)
			(layer "B.SilkS")
		)
		(fp_line
			(start -0.67945 -0.3048)
			(end -0.67945 0.3048)
			(stroke
				(width 0.1)
				(type default)
			)
			(layer "B.Fab")
		)
		(fp_line
			(start -0.67945 0.3048)
			(end -0.120396 0.3048)
			(stroke
				(width 0.1)
				(type default)
			)
			(layer "B.Fab")
		)
		(fp_line
			(start -0.12065 -0.3048)
			(end -0.67945 -0.3048)
			(stroke
				(width 0.1)
				(type default)
			)
			(layer "B.Fab")
		)
		(fp_line
			(start -0.12065 -0.2794)
			(end -0.12065 -0.3048)
			(stroke
				(width 0.1)
				(type default)
			)
			(layer "B.Fab")
		)
		(fp_line
			(start -0.120396 0.2794)
			(end 0.12065 0.2794)
			(stroke
				(width 0.1)
				(type default)
			)
			(layer "B.Fab")
		)
		(fp_line
			(start -0.120396 0.3048)
			(end -0.120396 0.2794)
			(stroke
				(width 0.1)
				(type default)
			)
			(layer "B.Fab")
		)
		(fp_line
			(start 0.12065 -0.305054)
			(end 0.12065 -0.2794)
			(stroke
				(width 0.1)
				(type default)
			)
			(layer "B.Fab")
		)
		(fp_line
			(start 0.12065 -0.2794)
			(end -0.12065 -0.2794)
			(stroke
				(width 0.1)
				(type default)
			)
			(layer "B.Fab")
		)
		(fp_line
			(start 0.12065 0.2794)
			(end 0.12065 0.3048)
			(stroke
				(width 0.1)
				(type default)
			)
			(layer "B.Fab")
		)
		(fp_line
			(start 0.12065 0.3048)
			(end 0.67945 0.3048)
			(stroke
				(width 0.1)
				(type default)
			)
			(layer "B.Fab")
		)
		(fp_line
			(start 0.67945 -0.305054)
			(end 0.12065 -0.305054)
			(stroke
				(width 0.1)
				(type default)
			)
			(layer "B.Fab")
		)
		(fp_line
			(start 0.67945 0.3048)
			(end 0.67945 -0.305054)
			(stroke
				(width 0.1)
				(type default)
			)
			(layer "B.Fab")
		)
		(pad "1" smd circle
			(at 0.40005 0 180)
			(size 0 0)
			(layers "B.Cu" "B.Mask" "B.Paste")
			(net "SMB_P52V_HPDB_SCL")
		)
		(pad "2" smd circle
			(at -0.40005 0 180)
			(size 0 0)
			(layers "B.Cu" "B.Mask" "B.Paste")
			(net "P3V3_AUX")
		)
	)
)
